# BASEBOARD_FAB2 (Tioga Pass) — schematic netlist excerpt (pin names and nets, part order shuffled) for the footprints in the layout excerpt that follows; sources: Cadence DE-HDL packaged netlist, KiCad conversion of Wiwynn_Tioga_Pass_MB.brd

C5T11  CAP_A  47UF 4V 20% X5R  pkg 0603V  page 217 : A = PVDDQ_ABC ; B = GND
R9F12  RES  10.0K 1% CHIP  pkg 0402  page 239 : A = P3V3_STBY ; B = PWRGD_P1V2_BMC_STBY_R
C5L6  CAP_A  47UF 4V 20% X5R  pkg 0603V  page 220 : A = PVDDQ_DEF ; B = GND

(kicad_pcb
	(version 20260206)
	(generator "pcbnew")
	(generator_version "10.0")
	(general
		(thickness 1.6)
		(legacy_teardrops no)
	)
	(paper "A4")
	(title_block
		(title "Wiwynn_Tioga_Pass_MB.brd")
		(comment 1 "Tioga Pass / footprints 4119-4121 of 4770")
	)
	(layers
		(0 "F.Cu" signal "TOP")
		(4 "In1.Cu" signal "L2GND")
		(6 "In2.Cu" signal "L3")
		(8 "In3.Cu" signal "L4GND")
		(10 "In4.Cu" signal "L5")
		(12 "In5.Cu" signal "L6GND")
		(14 "In6.Cu" signal "L7VCC")
		(16 "In7.Cu" signal "L8VCC")
		(18 "In8.Cu" signal "L9GND")
		(20 "In9.Cu" signal "L10")
		(22 "In10.Cu" signal "L11GND")
		(24 "In11.Cu" signal "L12")
		(26 "In12.Cu" signal "L13GND")
		(2 "B.Cu" signal "BOTTOM")
		(9 "F.Adhes" user "F.Adhesive")
		(11 "B.Adhes" user "B.Adhesive")
		(13 "F.Paste" user "Package Geometry/Pastemask Top")
		(15 "B.Paste" user "Package Geometry/Pastemask Bottom")
		(5 "F.SilkS" user "Ref Des/Silkscreen Top")
		(7 "B.SilkS" user "Ref Des/Silkscreen Bottom")
		(1 "F.Mask" user "Board Geometry/Soldermask Top")
		(3 "B.Mask" user "Board Geometry/Soldermask Bottom")
		(17 "Dwgs.User" user "User.Drawings")
		(19 "Cmts.User" user "User.Comments")
		(21 "Eco1.User" user "User.Eco1")
		(23 "Eco2.User" user "User.Eco2")
		(25 "Edge.Cuts" user "Board Geometry/Outline")
		(27 "Margin" user)
		(31 "F.CrtYd" user "Package Geometry/Place Bound Top")
		(29 "B.CrtYd" user "Package Geometry/Place Bound Bottom")
		(35 "F.Fab" user "Ref Des/Assembly Top")
		(33 "B.Fab" user "Ref Des/Assembly Bottom")
	)
	(footprint ""
		(layer "B.Cu")
		(at 474.218 -38.354 -90)
		(property "Reference" "R9F12"
			(at 0 0 90)
			(layer "B.SilkS")
			(hide yes)
			(effects
				(font
					(size 1.27 1.27)
				)
				(justify mirror)
			)
		)
		(property "Value" ""
			(at 0 0 90)
			(layer "B.Fab")
			(effects
				(font
					(size 1.27 1.27)
				)
				(justify mirror)
			)
		)
		(duplicate_pad_numbers_are_jumpers no)
		(fp_poly
			(pts
				(xy 0.2794 -0.1016) (xy -0.2794 -0.1016) (xy -0.2794 0.9906) (xy 0.2794 0.9906)
			)
			(stroke
				(width 0)
				(type default)
			)
			(fill no)
			(layer "B.CrtYd")
		)
		(fp_line
			(start -0.2794 0.9906)
			(end -0.2794 -0.1016)
			(stroke
				(width 0.1)
				(type default)
			)
			(layer "B.Fab")
		)
		(fp_line
			(start 0.2794 0.9906)
			(end -0.2794 0.9906)
			(stroke
				(width 0.1)
				(type default)
			)
			(layer "B.Fab")
		)
		(fp_line
			(start -0.2794 -0.1016)
			(end 0.2794 -0.1016)
			(stroke
				(width 0.1)
				(type default)
			)
			(layer "B.Fab")
		)
		(fp_line
			(start 0.2794 -0.1016)
			(end 0.2794 0.9906)
			(stroke
				(width 0.1)
				(type default)
			)
			(layer "B.Fab")
		)
		(pad "1" smd rect
			(at 0 0 90)
			(size 0.508 0.508)
			(layers "B.Cu" "B.Mask" "B.Paste")
			(net "P3V3_STBY")
		)
		(pad "2" smd rect
			(at 0 0.889 90)
			(size 0.508 0.508)
			(layers "B.Cu" "B.Mask" "B.Paste")
			(net "PWRGD_P1V2_BMC_STBY_R")
		)
		(zone
			(layer "B.Cu")
			(hatch none 0.5)
			(connect_pads
				(clearance 0)
			)
			(min_thickness 0.25)
			(keepout
				(tracks not_allowed)
				(vias allowed)
				(pads allowed)
				(copperpour not_allowed)
				(footprints allowed)
			)
			(placement
				(enabled no)
				(sheetname "")
			)
			(fill
				(thermal_gap 0.5)
				(thermal_bridge_width 0.5)
				(island_removal_mode 0)
			)
			(polygon
				(pts
					(xy 473.583 -38.1) (xy 473.583 -38.608) (xy 473.964 -38.608) (xy 473.964 -38.1)
				)
			)
		)
		(zone
			(layer "B.Cu")
			(hatch none 0.5)
			(connect_pads
				(clearance 0)
			)
			(min_thickness 0.25)
			(keepout
				(tracks allowed)
				(vias not_allowed)
				(pads allowed)
				(copperpour not_allowed)
				(footprints allowed)
			)
			(placement
				(enabled no)
				(sheetname "")
			)
			(fill
				(thermal_gap 0.5)
				(thermal_bridge_width 0.5)
				(island_removal_mode 0)
			)
			(polygon
				(pts
					(xy 473.964 -38.1) (xy 473.964 -38.608) (xy 473.583 -38.608) (xy 473.583 -38.1)
				)
			)
		)
	)
	(footprint ""
		(layer "B.Cu")
		(at 248.8565 -17.7546 -90)
		(property "Reference" "C5T11"
			(at -1.848866 0.752348 270)
			(unlocked yes)
			(layer "B.SilkS")
			(effects
				(font
					(size 1.27 0.9652)
					(thickness 0.1524)
				)
				(justify mirror)
			)
		)
		(property "Value" ""
			(at 0 0 90)
			(layer "B.Fab")
			(effects
				(font
					(size 1.27 1.27)
				)
				(justify mirror)
			)
		)
		(duplicate_pad_numbers_are_jumpers no)
		(fp_rect
			(start 0.500126 1.598422)
			(end -0.500126 -0.201422)
			(stroke
				(width 0)
				(type default)
			)
			(fill no)
			(layer "B.CrtYd")
		)
		(fp_line
			(start -0.500126 1.598422)
			(end 0.500126 1.598422)
			(stroke
				(width 0.1)
				(type default)
			)
			(layer "B.Fab")
		)
		(fp_line
			(start 0.500126 1.598422)
			(end 0.500126 -0.201422)
			(stroke
				(width 0.1)
				(type default)
			)
			(layer "B.Fab")
		)
		(fp_line
			(start -0.500126 -0.201422)
			(end -0.500126 1.598422)
			(stroke
				(width 0.1)
				(type default)
			)
			(layer "B.Fab")
		)
		(fp_line
			(start 0.500126 -0.201422)
			(end -0.500126 -0.201422)
			(stroke
				(width 0.1)
				(type default)
			)
			(layer "B.Fab")
		)
		(pad "1" smd rect
			(at 0 0 180)
			(size 0.889 0.9906)
			(layers "B.Cu" "B.Mask" "B.Paste")
			(net "PVDDQ_ABC")
		)
		(pad "2" smd rect
			(at 0 1.397 180)
			(size 0.889 0.9906)
			(layers "B.Cu" "B.Mask" "B.Paste")
			(net "GND")
		)
		(zone
			(layer "B.Cu")
			(hatch none 0.5)
			(connect_pads
				(clearance 0)
			)
			(min_thickness 0.25)
			(keepout
				(tracks not_allowed)
				(vias allowed)
				(pads allowed)
				(copperpour not_allowed)
				(footprints allowed)
			)
			(placement
				(enabled no)
				(sheetname "")
			)
			(fill
				(thermal_gap 0.5)
				(thermal_bridge_width 0.5)
				(island_removal_mode 0)
			)
			(polygon
				(pts
					(xy 247.904 -17.2593) (xy 248.412 -17.2593) (xy 248.412 -18.2499) (xy 247.904 -18.2499)
				)
			)
		)
		(zone
			(layer "B.Cu")
			(hatch none 0.5)
			(connect_pads
				(clearance 0)
			)
			(min_thickness 0.25)
			(keepout
				(tracks allowed)
				(vias not_allowed)
				(pads allowed)
				(copperpour not_allowed)
				(footprints allowed)
			)
			(placement
				(enabled no)
				(sheetname "")
			)
			(fill
				(thermal_gap 0.5)
				(thermal_bridge_width 0.5)
				(island_removal_mode 0)
			)
			(polygon
				(pts
					(xy 247.904 -17.2593) (xy 248.412 -17.2593) (xy 248.412 -18.2499) (xy 247.904 -18.2499)
				)
			)
		)
	)
	(footprint ""
		(layer "B.Cu")
		(at 276.000464 -145.0086 90)
		(property "Reference" "C5L6"
			(at -1.848866 0.752348 90)
			(unlocked yes)
			(layer "B.SilkS")
			(effects
				(font
					(size 1.27 0.9652)
					(thickness 0.1524)
				)
				(justify mirror)
			)
		)
		(property "Value" ""
			(at 0 0 90)
			(layer "B.Fab")
			(effects
				(font
					(size 1.27 1.27)
				)
				(justify mirror)
			)
		)
		(duplicate_pad_numbers_are_jumpers no)
		(fp_rect
			(start 0.500126 1.598422)
			(end -0.500126 -0.201422)
			(stroke
				(width 0)
				(type default)
			)
			(fill no)
			(layer "B.CrtYd")
		)
		(fp_line
			(start 0.500126 -0.201422)
			(end -0.500126 -0.201422)
			(stroke
				(width 0.1)
				(type default)
			)
			(layer "B.Fab")
		)
		(fp_line
			(start -0.500126 -0.201422)
			(end -0.500126 1.598422)
			(stroke
				(width 0.1)
				(type default)
			)
			(layer "B.Fab")
		)
		(fp_line
			(start 0.500126 1.598422)
			(end 0.500126 -0.201422)
			(stroke
				(width 0.1)
				(type default)
			)
			(layer "B.Fab")
		)
		(fp_line
			(start -0.500126 1.598422)
			(end 0.500126 1.598422)
			(stroke
				(width 0.1)
				(type default)
			)
			(layer "B.Fab")
		)
		(pad "1" smd rect
			(at 0 0)
			(size 0.889 0.9906)
			(layers "B.Cu" "B.Mask" "B.Paste")
			(net "PVDDQ_DEF")
		)
		(pad "2" smd rect
			(at 0 1.397)
			(size 0.889 0.9906)
			(layers "B.Cu" "B.Mask" "B.Paste")
			(net "GND")
		)
		(zone
			(layer "B.Cu")
			(hatch none 0.5)
			(connect_pads
				(clearance 0)
			)
			(min_thickness 0.25)
			(keepout
				(tracks not_allowed)
				(vias allowed)
				(pads allowed)
				(copperpour not_allowed)
				(footprints allowed)
			)
			(placement
				(enabled no)
				(sheetname "")
			)
			(fill
				(thermal_gap 0.5)
				(thermal_bridge_width 0.5)
				(island_removal_mode 0)
			)
			(polygon
				(pts
					(xy 276.952964 -145.5039) (xy 276.444964 -145.5039) (xy 276.444964 -144.5133) (xy 276.952964 -144.5133)
				)
			)
		)
		(zone
			(layer "B.Cu")
			(hatch none 0.5)
			(connect_pads
				(clearance 0)
			)
			(min_thickness 0.25)
			(keepout
				(tracks allowed)
				(vias not_allowed)
				(pads allowed)
				(copperpour not_allowed)
				(footprints allowed)
			)
			(placement
				(enabled no)
				(sheetname "")
			)
			(fill
				(thermal_gap 0.5)
				(thermal_bridge_width 0.5)
				(island_removal_mode 0)
			)
			(polygon
				(pts
					(xy 276.952964 -145.5039) (xy 276.444964 -145.5039) (xy 276.444964 -144.5133) (xy 276.952964 -144.5133)
				)
			)
		)
	)
)
